(kicad_pcb
	(version 20241229)
	(generator "pcbnew")
	(generator_version "9.0")
	(general
		(thickness 1.61)
		(legacy_teardrops no)
	)
	(paper "A3")
	(title_block
		(title "RDIMM DDR5 Tester")
		(date "2026-05-21")
		(rev "2.2.0")
		(company "Antmicro")
		(comment 9 "footprints 183-186 of 796")
	)
	(layers
		(0 "F.Cu" signal)
		(4 "In1.Cu" power)
		(6 "In2.Cu" mixed)
		(8 "In3.Cu" power)
		(10 "In4.Cu" mixed)
		(12 "In5.Cu" power)
		(14 "In6.Cu" mixed)
		(16 "In7.Cu" power)
		(18 "In8.Cu" power)
		(20 "In9.Cu" mixed)
		(22 "In10.Cu" power)
		(2 "B.Cu" signal)
		(9 "F.Adhes" user "F.Adhesive")
		(11 "B.Adhes" user "B.Adhesive")
		(13 "F.Paste" user)
		(15 "B.Paste" user)
		(5 "F.SilkS" user "F.Silkscreen")
		(7 "B.SilkS" user "B.Silkscreen")
		(1 "F.Mask" user)
		(3 "B.Mask" user)
		(17 "Dwgs.User" user "User.Drawings")
		(19 "Cmts.User" user "User.Comments")
		(21 "Eco1.User" user "User.Eco1")
		(23 "Eco2.User" user "User.Eco2")
		(25 "Edge.Cuts" user)
		(27 "Margin" user)
		(31 "F.CrtYd" user "F.Courtyard")
		(29 "B.CrtYd" user "B.Courtyard")
		(35 "F.Fab" user)
		(33 "B.Fab" user)
	)
	(footprint "antmicro-footprints:LED_0402_1005Metric_G"
		(layer "F.Cu")
		(at 109.73 114.725 180)
		(property "Reference" "D1"
			(at 0.805 -1.525 0)
			(unlocked yes)
			(layer "F.SilkS")
			(hide yes)
			(effects
				(font
					(size 0.7 0.7)
					(thickness 0.15)
				)
				(justify left bottom)
			)
		)
		(property "Value" "LED_G_0402_VLMTG1500-GS08"
			(at 0 1.5 180)
			(unlocked yes)
			(layer "F.Fab")
			(effects
				(font
					(size 0.7 0.7)
					(thickness 0.15)
				)
				(justify left bottom)
			)
		)
		(property "Datasheet" "https://www.vishay.com/docs/82554/vlmo1500.pdf"
			(at 0 0 180)
			(layer "F.Fab")
			(hide yes)
			(effects
				(font
					(size 1.27 1.27)
					(thickness 0.15)
				)
			)
		)
		(property "MPN" "VLMTG1500-GS08"
			(at 0 0 180)
			(unlocked yes)
			(layer "F.Fab")
			(hide yes)
			(effects
				(font
					(size 1 1)
					(thickness 0.15)
				)
			)
		)
		(property "Manufacturer" "Vishay"
			(at 0 0 180)
			(unlocked yes)
			(layer "F.Fab")
			(hide yes)
			(effects
				(font
					(size 1 1)
					(thickness 0.15)
				)
			)
		)
		(property "Color" "Green"
			(at 0 0 180)
			(unlocked yes)
			(layer "F.Fab")
			(hide yes)
			(effects
				(font
					(size 1 1)
					(thickness 0.15)
				)
			)
		)
		(property "Author" "Antmicro"
			(at 0 0 180)
			(unlocked yes)
			(layer "F.Fab")
			(hide yes)
			(effects
				(font
					(size 1 1)
					(thickness 0.15)
				)
			)
		)
		(property "License" "Apache-2.0"
			(at 0 0 180)
			(unlocked yes)
			(layer "F.Fab")
			(hide yes)
			(effects
				(font
					(size 1 1)
					(thickness 0.15)
				)
			)
		)
		(sheetname "/FPGA Config/")
		(sheetfile "fpga-config.kicad_sch")
		(attr smd)
		(fp_line
			(start -0.175 0.4)
			(end 0.175 0.4)
			(stroke
				(width 0.15)
				(type solid)
			)
			(layer "F.SilkS")
		)
		(fp_line
			(start -0.175 -0.4)
			(end 0.175 -0.4)
			(stroke
				(width 0.15)
				(type solid)
			)
			(layer "F.SilkS")
		)
		(fp_line
			(start -0.9 -0.4)
			(end -0.9 0.4)
			(stroke
				(width 0.15)
				(type solid)
			)
			(layer "F.SilkS")
		)
		(fp_rect
			(start -0.925 -0.47)
			(end 0.925 0.47)
			(stroke
				(width 0.05)
				(type default)
			)
			(fill no)
			(layer "F.CrtYd")
		)
		(fp_line
			(start 0.501 0.26)
			(end 0.501 -0.248)
			(stroke
				(width 0.15)
				(type solid)
			)
			(layer "F.Fab")
		)
		(fp_line
			(start 0.501 0.26)
			(end 0.501 -0.248)
			(stroke
				(width 0.15)
				(type solid)
			)
			(layer "F.Fab")
		)
		(fp_line
			(start 0.501 -0.248)
			(end 0.172 -0.248)
			(stroke
				(width 0.15)
				(type solid)
			)
			(layer "F.Fab")
		)
		(fp_line
			(start 0.501 -0.248)
			(end -0.489 -0.248)
			(stroke
				(width 0.15)
				(type solid)
			)
			(layer "F.Fab")
		)
		(fp_line
			(start 0.228 0.202)
			(end 0.228 0)
			(stroke
				(width 0.15)
				(type solid)
			)
			(layer "F.Fab")
		)
		(fp_line
			(start 0.228 0)
			(end 0.228 -0.202)
			(stroke
				(width 0.15)
				(type solid)
			)
			(layer "F.Fab")
		)
		(fp_line
			(start 0.228 -0.202)
			(end -0.074 0)
			(stroke
				(width 0.15)
				(type solid)
			)
			(layer "F.Fab")
		)
		(fp_line
			(start 0.172 0.26)
			(end 0.501 0.26)
			(stroke
				(width 0.15)
				(type solid)
			)
			(layer "F.Fab")
		)
		(fp_line
			(start 0.172 -0.248)
			(end 0.172 0.26)
			(stroke
				(width 0.15)
				(type solid)
			)
			(layer "F.Fab")
		)
		(fp_line
			(start -0.074 0)
			(end 0.228 0.202)
			(stroke
				(width 0.15)
				(type solid)
			)
			(layer "F.Fab")
		)
		(fp_line
			(start -0.158 0.26)
			(end -0.158 -0.248)
			(stroke
				(width 0.15)
				(type solid)
			)
			(layer "F.Fab")
		)
		(fp_line
			(start -0.158 -0.248)
			(end -0.489 -0.248)
			(stroke
				(width 0.15)
				(type solid)
			)
			(layer "F.Fab")
		)
		(fp_line
			(start -0.173 0.202)
			(end -0.173 0.102)
			(stroke
				(width 0.15)
				(type solid)
			)
			(layer "F.Fab")
		)
		(fp_line
			(start -0.173 -0.202)
			(end -0.173 0.102)
			(stroke
				(width 0.15)
				(type solid)
			)
			(layer "F.Fab")
		)
		(fp_line
			(start -0.489 0.26)
			(end 0.501 0.26)
			(stroke
				(width 0.15)
				(type solid)
			)
			(layer "F.Fab")
		)
		(fp_line
			(start -0.489 0.26)
			(end -0.158 0.26)
			(stroke
				(width 0.15)
				(type solid)
			)
			(layer "F.Fab")
		)
		(fp_line
			(start -0.489 -0.248)
			(end -0.489 0.26)
			(stroke
				(width 0.15)
				(type solid)
			)
			(layer "F.Fab")
		)
		(fp_line
			(start -0.489 -0.248)
			(end -0.489 0.26)
			(stroke
				(width 0.15)
				(type solid)
			)
			(layer "F.Fab")
		)
		(fp_text user "${REFERENCE}"
			(at 0 2.95 180)
			(unlocked yes)
			(layer "F.Fab")
			(effects
				(font
					(size 0.7 0.7)
					(thickness 0.15)
				)
				(justify left bottom)
			)
		)
		(fp_text user "License: Apache-2.0"
			(at 0 5.35 180)
			(layer "F.Fab")
			(effects
				(font
					(size 0.7 0.7)
					(thickness 0.15)
				)
				(justify left bottom)
			)
		)
		(fp_text user "Author: Antmicro"
			(at 0 4.15 180)
			(layer "F.Fab")
			(effects
				(font
					(size 0.7 0.7)
					(thickness 0.15)
				)
				(justify left bottom)
			)
		)
		(pad "1" smd roundrect
			(at -0.48 0 180)
			(size 0.59 0.64)
			(layers "F.Cu" "F.Mask" "F.Paste")
			(roundrect_rratio 0.25)
			(net 783 "Net-(D1-C)")
			(pinfunction "C")
			(pintype "passive")
		)
		(pad "2" smd roundrect
			(at 0.48 0 180)
			(size 0.59 0.64)
			(layers "F.Cu" "F.Mask" "F.Paste")
			(roundrect_rratio 0.25)
			(net 151 "+3V3")
			(pinfunction "A")
			(pintype "passive")
		)
	)
	(footprint "antmicro-footprints:C_0402_1005Metric"
		(layer "F.Cu")
		(at 244.25 186.349 -90)
		(descr "Capacitor SMD 0402")
		(tags "capacitor SMD 0402")
		(property "Reference" "C320"
			(at 0.226 -1.35 90)
			(layer "F.SilkS")
			(effects
				(font
					(size 0.7 0.7)
					(thickness 0.15)
				)
				(justify right bottom)
			)
		)
		(property "Value" "C_100n_0402"
			(at -1.022927 2.155213 90)
			(layer "F.Fab")
			(effects
				(font
					(size 0.7 0.7)
					(thickness 0.15)
				)
				(justify right bottom)
			)
		)
		(property "Datasheet" "https://www.murata.com/products/productdetail?partno=GRM155R61H104KE14%23"
			(at 0 0 270)
			(layer "F.Fab")
			(hide yes)
			(effects
				(font
					(size 1.27 1.27)
					(thickness 0.15)
				)
			)
		)
		(property "Manufacturer" "Murata"
			(at 0 0 270)
			(unlocked yes)
			(layer "F.Fab")
			(hide yes)
			(effects
				(font
					(size 1 1)
					(thickness 0.15)
				)
			)
		)
		(property "MPN" "GRM155R61H104KE14D"
			(at 0 0 270)
			(unlocked yes)
			(layer "F.Fab")
			(hide yes)
			(effects
				(font
					(size 1 1)
					(thickness 0.15)
				)
			)
		)
		(property "Val" "100n"
			(at 0 0 270)
			(unlocked yes)
			(layer "F.Fab")
			(hide yes)
			(effects
				(font
					(size 1 1)
					(thickness 0.15)
				)
			)
		)
		(property "License" "Apache-2.0"
			(at 0 0 270)
			(unlocked yes)
			(layer "F.Fab")
			(hide yes)
			(effects
				(font
					(size 1 1)
					(thickness 0.15)
				)
			)
		)
		(property "Author" "Antmicro"
			(at 0 0 270)
			(unlocked yes)
			(layer "F.Fab")
			(hide yes)
			(effects
				(font
					(size 1 1)
					(thickness 0.15)
				)
			)
		)
		(property "Voltage" "50V"
			(at 0 0 270)
			(unlocked yes)
			(layer "F.Fab")
			(hide yes)
			(effects
				(font
					(size 1 1)
					(thickness 0.15)
				)
			)
		)
		(property "Dielectric" "X5R"
			(at 0 0 270)
			(unlocked yes)
			(layer "F.Fab")
			(hide yes)
			(effects
				(font
					(size 1 1)
					(thickness 0.15)
				)
			)
		)
		(sheetname "/I^{2}C + I3C/")
		(sheetfile "i2c.kicad_sch")
		(attr smd)
		(fp_rect
			(start -0.925 -0.47)
			(end 0.925 0.47)
			(stroke
				(width 0.05)
				(type default)
			)
			(fill no)
			(layer "F.CrtYd")
		)
		(fp_line
			(start -0.494 0.248)
			(end -0.494 -0.25)
			(stroke
				(width 0.15)
				(type solid)
			)
			(layer "F.Fab")
		)
		(fp_line
			(start 0.504 0.248)
			(end -0.494 0.248)
			(stroke
				(width 0.15)
				(type solid)
			)
			(layer "F.Fab")
		)
		(fp_line
			(start -0.494 -0.25)
			(end 0.504 -0.25)
			(stroke
				(width 0.15)
				(type solid)
			)
			(layer "F.Fab")
		)
		(fp_line
			(start 0.504 -0.25)
			(end 0.504 0.248)
			(stroke
				(width 0.15)
				(type solid)
			)
			(layer "F.Fab")
		)
		(fp_text user "License: Apache-2.0"
			(at -0.939 5.799 270)
			(layer "F.Fab")
			(effects
				(font
					(size 0.7 0.7)
					(thickness 0.15)
				)
				(justify left bottom)
			)
		)
		(fp_text user "Author: Antmicro"
			(at -0.939 3.399 270)
			(layer "F.Fab")
			(effects
				(font
					(size 0.7 0.7)
					(thickness 0.15)
				)
				(justify left bottom)
			)
		)
		(fp_text user "${REFERENCE}"
			(at -0.939 4.599 270)
			(layer "F.Fab")
			(effects
				(font
					(size 0.7 0.7)
					(thickness 0.15)
				)
				(justify left bottom)
			)
		)
		(pad "1" smd roundrect
			(at -0.48 0 270)
			(size 0.59 0.64)
			(layers "F.Cu" "F.Mask" "F.Paste")
			(roundrect_rratio 0.25)
			(net 774 "Net-(U49-EN)")
			(pintype "passive")
		)
		(pad "2" smd roundrect
			(at 0.48 0 270)
			(size 0.59 0.64)
			(layers "F.Cu" "F.Mask" "F.Paste")
			(roundrect_rratio 0.25)
			(net 1 "GND")
			(pintype "passive")
		)
	)
	(footprint "antmicro-footprints:Vishay_PowerPAK_1212-8_Single"
		(layer "F.Cu")
		(at 149.78 190.955 -90)
		(descr "PowerPAK 1212-8 Single")
		(tags "Vishay PowerPAK 1212-8 Single")
		(property "Reference" "Q13"
			(at -2.255 -1.57 180)
			(layer "F.SilkS")
			(effects
				(font
					(size 0.7 0.7)
					(thickness 0.15)
				)
				(justify right bottom)
			)
		)
		(property "Value" "SI7613DN-T1-GE3"
			(at 0 2.7 90)
			(layer "F.Fab")
			(hide yes)
			(effects
				(font
					(size 0.7 0.7)
					(thickness 0.15)
				)
				(justify right bottom)
			)
		)
		(property "Datasheet" "https://www.vishay.com/docs/64809/si7613dn.pdf"
			(at 0 0 270)
			(layer "F.Fab")
			(hide yes)
			(effects
				(font
					(size 1.27 1.27)
					(thickness 0.15)
				)
			)
		)
		(property "MPN" "SI7613DN-T1-GE3"
			(at 0 0 270)
			(unlocked yes)
			(layer "F.Fab")
			(hide yes)
			(effects
				(font
					(size 1 1)
					(thickness 0.15)
				)
			)
		)
		(property "Manufacturer" "Vishay"
			(at 0 0 270)
			(unlocked yes)
			(layer "F.Fab")
			(hide yes)
			(effects
				(font
					(size 1 1)
					(thickness 0.15)
				)
			)
		)
		(property "Author" "Antmicro"
			(at 0 0 270)
			(unlocked yes)
			(layer "F.Fab")
			(hide yes)
			(effects
				(font
					(size 1 1)
					(thickness 0.15)
				)
			)
		)
		(property "License" "Apache-2.0"
			(at 0 0 270)
			(unlocked yes)
			(layer "F.Fab")
			(hide yes)
			(effects
				(font
					(size 1 1)
					(thickness 0.15)
				)
			)
		)
		(sheetname "/Supply/")
		(sheetfile "supply.kicad_sch")
		(attr smd)
		(fp_line
			(start -1.635 1.634)
			(end 1.634 1.634)
			(stroke
				(width 0.15)
				(type solid)
			)
			(layer "F.SilkS")
		)
		(fp_line
			(start -1.635 1.3)
			(end -1.635 1.634)
			(stroke
				(width 0.15)
				(type solid)
			)
			(layer "F.SilkS")
		)
		(fp_line
			(start 1.634 1.3)
			(end 1.634 1.634)
			(stroke
				(width 0.15)
				(type solid)
			)
			(layer "F.SilkS")
		)
		(fp_line
			(start -1.651 -1.651)
			(end -1.651 -1.317)
			(stroke
				(width 0.15)
				(type solid)
			)
			(layer "F.SilkS")
		)
		(fp_line
			(start -1.651 -1.651)
			(end 1.648 -1.651)
			(stroke
				(width 0.15)
				(type solid)
			)
			(layer "F.SilkS")
		)
		(fp_line
			(start 1.648 -1.651)
			(end 1.648 -1.317)
			(stroke
				(width 0.15)
				(type solid)
			)
			(layer "F.SilkS")
		)
		(fp_circle
			(center -1.9 -1.4)
			(end -1.85 -1.4)
			(stroke
				(width 0.15)
				(type solid)
			)
			(fill yes)
			(layer "F.SilkS")
		)
		(fp_rect
			(start -2 -1.8)
			(end 2 1.798)
			(stroke
				(width 0.05)
				(type solid)
			)
			(fill no)
			(layer "F.CrtYd")
		)
		(fp_line
			(start -1.6425 -1.4175)
			(end -1.4175 -1.6425)
			(stroke
				(width 0.15)
				(type solid)
			)
			(layer "F.Fab")
		)
		(fp_rect
			(start -1.651 -1.651)
			(end 1.648 1.648)
			(stroke
				(width 0.15)
				(type solid)
			)
			(fill no)
			(layer "F.Fab")
		)
		(fp_text user "Author: Antmicro"
			(at -8 5.9 270)
			(layer "F.Fab")
			(effects
				(font
					(size 0.7 0.7)
					(thickness 0.15)
				)
				(justify left bottom)
			)
		)
		(fp_text user "${REFERENCE}"
			(at -8 4.7 270)
			(layer "F.Fab")
			(effects
				(font
					(size 0.7 0.7)
					(thickness 0.15)
				)
				(justify left bottom)
			)
		)
		(fp_text user "License: Apache-2.0"
			(at -8 7.1 270)
			(layer "F.Fab")
			(effects
				(font
					(size 0.7 0.7)
					(thickness 0.15)
				)
				(justify left bottom)
			)
		)
		(pad "1" smd rect
			(at -1.436 -0.99 270)
			(size 0.99 0.405)
			(layers "F.Cu" "F.Mask" "F.Paste")
			(net 35 "VDC")
			(pinfunction "S")
			(pintype "passive")
		)
		(pad "2" smd rect
			(at -1.436 -0.332 270)
			(size 0.99 0.405)
			(layers "F.Cu" "F.Mask" "F.Paste")
			(net 35 "VDC")
			(pinfunction "S")
			(pintype "passive")
		)
		(pad "3" smd rect
			(at -1.436 0.33 270)
			(size 0.99 0.405)
			(layers "F.Cu" "F.Mask" "F.Paste")
			(net 35 "VDC")
			(pinfunction "S")
			(pintype "passive")
		)
		(pad "4" smd rect
			(at -1.436 0.988 270)
			(size 0.99 0.405)
			(layers "F.Cu" "F.Mask" "F.Paste")
			(net 285 "Net-(Q13-G)")
			(pinfunction "G")
			(pintype "passive")
		)
		(pad "5" smd custom
			(at 0.557 0 270)
			(size 1.725 2.235)
			(layers "F.Cu" "F.Mask" "F.Paste")
			(net 324 "/Supply/12V_PCIE_fused")
			(pinfunction "D")
			(pintype "passive")
			(zone_connect 2)
			(options
				(clearance outline)
				(anchor rect)
			)
			(primitives
				(gr_poly
					(pts
						(xy 0.8625 0.1275) (xy 0.8625 -0.1275) (xy 1.3725 -0.1275) (xy 1.3725 -0.5325) (xy 0.8625 -0.5325)
						(xy 0.8625 -0.7875) (xy 1.3725 -0.7875) (xy 1.3725 -1.195) (xy 0.6125 -1.195) (xy 0.6125 1.195)
						(xy 1.3725 1.195) (xy 1.3725 0.7875) (xy 0.8625 0.7875) (xy 0.8625 0.5325) (xy 1.3725 0.5325)
						(xy 1.3725 0.1275)
					)
					(width 0)
					(fill yes)
				)
			)
		)
	)
	(footprint "antmicro-footprints:R_0402_1005Metric"
		(layer "F.Cu")
		(at 252.785 146.65 180)
		(descr "Resistor SMD 0402")
		(tags "resistor SMD 0402")
		(property "Reference" "R61"
			(at -1.122484 -1.35 0)
			(layer "F.SilkS")
			(effects
				(font
					(size 0.7 0.7)
					(thickness 0.15)
				)
				(justify right bottom)
			)
		)
		(property "Value" "R_330R_0402"
			(at -1.011843 1.772047 0)
			(layer "F.Fab")
			(effects
				(font
					(size 0.7 0.7)
					(thickness 0.15)
				)
				(justify right bottom)
			)
		)
		(property "Datasheet" "https://www.bourns.com/docs/product-datasheets/cr.pdf"
			(at 0 0 180)
			(layer "F.Fab")
			(hide yes)
			(effects
				(font
					(size 1.27 1.27)
					(thickness 0.15)
				)
			)
		)
		(property "Manufacturer" "Bourns"
			(at 0 0 180)
			(unlocked yes)
			(layer "F.Fab")
			(hide yes)
			(effects
				(font
					(size 1 1)
					(thickness 0.15)
				)
			)
		)
		(property "MPN" "CR0402-FX-3300GLF"
			(at 0 0 180)
			(unlocked yes)
			(layer "F.Fab")
			(hide yes)
			(effects
				(font
					(size 1 1)
					(thickness 0.15)
				)
			)
		)
		(property "Val" "330R"
			(at 0 0 180)
			(unlocked yes)
			(layer "F.Fab")
			(hide yes)
			(effects
				(font
					(size 1 1)
					(thickness 0.15)
				)
			)
		)
		(property "License" "Apache-2.0"
			(at 0 0 180)
			(unlocked yes)
			(layer "F.Fab")
			(hide yes)
			(effects
				(font
					(size 1 1)
					(thickness 0.15)
				)
			)
		)
		(property "Author" "Antmicro"
			(at 0 0 180)
			(unlocked yes)
			(layer "F.Fab")
			(hide yes)
			(effects
				(font
					(size 1 1)
					(thickness 0.15)
				)
			)
		)
		(property "Tolerance" "1%"
			(at 0 0 180)
			(unlocked yes)
			(layer "F.Fab")
			(hide yes)
			(effects
				(font
					(size 1 1)
					(thickness 0.15)
				)
			)
		)
		(sheetname "/DDR5 RDIMM/")
		(sheetfile "ddr5-rdimm.kicad_sch")
		(attr smd)
		(fp_rect
			(start -0.925 -0.47)
			(end 0.925 0.47)
			(stroke
				(width 0.05)
				(type default)
			)
			(fill no)
			(layer "F.CrtYd")
		)
		(fp_rect
			(start -0.5 -0.25)
			(end 0.5 0.25)
			(stroke
				(width 0.15)
				(type solid)
			)
			(fill no)
			(layer "F.Fab")
		)
		(fp_text user "${REFERENCE}"
			(at -0.95 3.168 180)
			(layer "F.Fab")
			(effects
				(font
					(size 0.7 0.7)
					(thickness 0.15)
				)
				(justify left bottom)
			)
		)
		(fp_text user "License: Apache-2.0"
			(at -0.95 5.169 180)
			(layer "F.Fab")
			(effects
				(font
					(size 0.7 0.7)
					(thickness 0.15)
				)
				(justify left bottom)
			)
		)
		(fp_text user "Author: Antmicro"
			(at -0.95 4.169 180)
			(layer "F.Fab")
			(effects
				(font
					(size 0.7 0.7)
					(thickness 0.15)
				)
				(justify left bottom)
			)
		)
		(pad "1" smd roundrect
			(at -0.48 0 180)
			(size 0.59 0.64)
			(layers "F.Cu" "F.Mask" "F.Paste")
			(roundrect_rratio 0.25)
			(net 237 "Net-(D20-C_{Y})")
			(pintype "passive")
		)
		(pad "2" smd roundrect
			(at 0.48 0 180)
			(size 0.59 0.64)
			(layers "F.Cu" "F.Mask" "F.Paste")
			(roundrect_rratio 0.25)
			(net 277 "Net-(Q9-D)")
			(pintype "passive")
		)
	)
)
